# S9S_MB_2U (Grand Teton) — schematic netlist excerpt (pin names and nets, part order shuffled) for the footprints in the layout excerpt that follows; sources: Cadence DE-HDL packaged netlist, KiCad conversion of 03242023_DA0F0TMBIJ0_F0T_Motherboard_J_brd_V01_OCP.brd

R1812  Q_RES  33.2 1% CHIP  pkg 0402LF  page 222 : A = IRQ_SGPIO_INTR_N ; B = IRQ_SGPIO_INTR_N_R
R3672  Q_RES  0 5% CHIP  pkg 0402LF  page 250 : A = SMB_VR_3V3AUX_SCL_R1 ; B = SMB_SEN_TIC_3V3AUX_SCL

(kicad_pcb
	(version 20260206)
	(generator "pcbnew")
	(generator_version "10.0")
	(general
		(thickness 1.6)
		(legacy_teardrops no)
	)
	(paper "A4")
	(title_block
		(title "03242023_DA0F0TMBIJ0_F0T_Motherboard_J_brd_V01_OCP.brd")
		(comment 1 "Grand Teton / footprints 4018-4019 of 6105")
	)
	(layers
		(0 "F.Cu" signal "TOP")
		(4 "In1.Cu" signal "GND")
		(6 "In2.Cu" signal "IN1")
		(8 "In3.Cu" signal "GND1")
		(10 "In4.Cu" signal "IN2")
		(12 "In5.Cu" signal "GND2")
		(14 "In6.Cu" signal "IN3")
		(16 "In7.Cu" signal "GND3")
		(18 "In8.Cu" signal "VCC")
		(20 "In9.Cu" signal "VCC1")
		(22 "In10.Cu" signal "GND4")
		(24 "In11.Cu" signal "IN4")
		(26 "In12.Cu" signal "GND5")
		(28 "In13.Cu" signal "IN5")
		(30 "In14.Cu" signal "GND6")
		(32 "In15.Cu" signal "IN6")
		(34 "In16.Cu" signal "GND7")
		(2 "B.Cu" signal "BOTTOM")
		(9 "F.Adhes" user "F.Adhesive")
		(11 "B.Adhes" user "B.Adhesive")
		(13 "F.Paste" user "Package Geometry/Pastemask Top")
		(15 "B.Paste" user "Package Geometry/Pastemask Bottom")
		(5 "F.SilkS" user "Ref Des/Silkscreen Top")
		(7 "B.SilkS" user "Ref Des/Silkscreen Bottom")
		(1 "F.Mask" user "Board Geometry/Soldermask Top")
		(3 "B.Mask" user "Board Geometry/Soldermask Bottom")
		(17 "Dwgs.User" user "User.Drawings")
		(19 "Cmts.User" user "User.Comments")
		(21 "Eco1.User" user "User.Eco1")
		(23 "Eco2.User" user "User.Eco2")
		(25 "Edge.Cuts" user "Board Geometry/Outline")
		(27 "Margin" user)
		(31 "F.CrtYd" user "Package Geometry/Place Bound Top")
		(29 "B.CrtYd" user "Package Geometry/Place Bound Bottom")
		(35 "F.Fab" user "Ref Des/Assembly Top")
		(33 "B.Fab" user "Ref Des/Assembly Bottom")
	)
	(footprint ""
		(layer "F.Cu")
		(at 193.38036 -115.534948 180)
		(property "Reference" "R1812"
			(at 0 0 180)
			(layer "F.SilkS")
			(hide yes)
			(effects
				(font
					(size 1.27 1.27)
				)
			)
		)
		(property "Value" ""
			(at 0 0 180)
			(layer "F.Fab")
			(effects
				(font
					(size 1.27 1.27)
				)
			)
		)
		(duplicate_pad_numbers_are_jumpers no)
		(fp_line
			(start 0.7874 0.4064)
			(end -0.7874 0.4064)
			(stroke
				(width 0.1524)
				(type default)
			)
			(layer "F.SilkS")
		)
		(fp_line
			(start 0.7874 -0.4064)
			(end 0.7874 0.4064)
			(stroke
				(width 0.1524)
				(type default)
			)
			(layer "F.SilkS")
		)
		(fp_line
			(start -0.7874 0.4064)
			(end -0.7874 -0.4064)
			(stroke
				(width 0.1524)
				(type default)
			)
			(layer "F.SilkS")
		)
		(fp_line
			(start -0.7874 -0.4064)
			(end 0.7874 -0.4064)
			(stroke
				(width 0.1524)
				(type default)
			)
			(layer "F.SilkS")
		)
		(fp_line
			(start 0.67945 0.3048)
			(end 0.120396 0.3048)
			(stroke
				(width 0.1)
				(type default)
			)
			(layer "F.Fab")
		)
		(fp_line
			(start 0.67945 -0.3048)
			(end 0.67945 0.3048)
			(stroke
				(width 0.1)
				(type default)
			)
			(layer "F.Fab")
		)
		(fp_line
			(start 0.12065 -0.2794)
			(end 0.12065 -0.3048)
			(stroke
				(width 0.1)
				(type default)
			)
			(layer "F.Fab")
		)
		(fp_line
			(start 0.12065 -0.3048)
			(end 0.67945 -0.3048)
			(stroke
				(width 0.1)
				(type default)
			)
			(layer "F.Fab")
		)
		(fp_line
			(start 0.120396 0.3048)
			(end 0.120396 0.2794)
			(stroke
				(width 0.1)
				(type default)
			)
			(layer "F.Fab")
		)
		(fp_line
			(start 0.120396 0.2794)
			(end -0.12065 0.2794)
			(stroke
				(width 0.1)
				(type default)
			)
			(layer "F.Fab")
		)
		(fp_line
			(start -0.12065 0.3048)
			(end -0.67945 0.3048)
			(stroke
				(width 0.1)
				(type default)
			)
			(layer "F.Fab")
		)
		(fp_line
			(start -0.12065 0.2794)
			(end -0.12065 0.3048)
			(stroke
				(width 0.1)
				(type default)
			)
			(layer "F.Fab")
		)
		(fp_line
			(start -0.12065 -0.2794)
			(end 0.12065 -0.2794)
			(stroke
				(width 0.1)
				(type default)
			)
			(layer "F.Fab")
		)
		(fp_line
			(start -0.12065 -0.305054)
			(end -0.12065 -0.2794)
			(stroke
				(width 0.1)
				(type default)
			)
			(layer "F.Fab")
		)
		(fp_line
			(start -0.67945 0.3048)
			(end -0.67945 -0.305054)
			(stroke
				(width 0.1)
				(type default)
			)
			(layer "F.Fab")
		)
		(fp_line
			(start -0.67945 -0.305054)
			(end -0.12065 -0.305054)
			(stroke
				(width 0.1)
				(type default)
			)
			(layer "F.Fab")
		)
		(pad "1" smd circle
			(at -0.40005 0 180)
			(size 0 0)
			(layers "F.Cu" "F.Mask" "F.Paste")
			(net "IRQ_SGPIO_INTR_N")
		)
		(pad "2" smd circle
			(at 0.40005 0 180)
			(size 0 0)
			(layers "F.Cu" "F.Mask" "F.Paste")
			(net "IRQ_SGPIO_INTR_N_R")
		)
	)
	(footprint ""
		(layer "F.Cu")
		(at 22.809454 -111.383826)
		(property "Reference" "R3672"
			(at 0 0 0)
			(layer "F.SilkS")
			(hide yes)
			(effects
				(font
					(size 1.27 1.27)
				)
			)
		)
		(property "Value" ""
			(at 0 0 0)
			(layer "F.Fab")
			(effects
				(font
					(size 1.27 1.27)
				)
			)
		)
		(duplicate_pad_numbers_are_jumpers no)
		(fp_line
			(start -0.7874 -0.4064)
			(end 0.7874 -0.4064)
			(stroke
				(width 0.1524)
				(type default)
			)
			(layer "F.SilkS")
		)
		(fp_line
			(start -0.7874 0.4064)
			(end -0.7874 -0.4064)
			(stroke
				(width 0.1524)
				(type default)
			)
			(layer "F.SilkS")
		)
		(fp_line
			(start 0.7874 -0.4064)
			(end 0.7874 0.4064)
			(stroke
				(width 0.1524)
				(type default)
			)
			(layer "F.SilkS")
		)
		(fp_line
			(start 0.7874 0.4064)
			(end -0.7874 0.4064)
			(stroke
				(width 0.1524)
				(type default)
			)
			(layer "F.SilkS")
		)
		(fp_line
			(start -0.67945 -0.305054)
			(end -0.12065 -0.305054)
			(stroke
				(width 0.1)
				(type default)
			)
			(layer "F.Fab")
		)
		(fp_line
			(start -0.67945 0.3048)
			(end -0.67945 -0.305054)
			(stroke
				(width 0.1)
				(type default)
			)
			(layer "F.Fab")
		)
		(fp_line
			(start -0.12065 -0.305054)
			(end -0.12065 -0.2794)
			(stroke
				(width 0.1)
				(type default)
			)
			(layer "F.Fab")
		)
		(fp_line
			(start -0.12065 -0.2794)
			(end 0.12065 -0.2794)
			(stroke
				(width 0.1)
				(type default)
			)
			(layer "F.Fab")
		)
		(fp_line
			(start -0.12065 0.2794)
			(end -0.12065 0.3048)
			(stroke
				(width 0.1)
				(type default)
			)
			(layer "F.Fab")
		)
		(fp_line
			(start -0.12065 0.3048)
			(end -0.67945 0.3048)
			(stroke
				(width 0.1)
				(type default)
			)
			(layer "F.Fab")
		)
		(fp_line
			(start 0.120396 0.2794)
			(end -0.12065 0.2794)
			(stroke
				(width 0.1)
				(type default)
			)
			(layer "F.Fab")
		)
		(fp_line
			(start 0.120396 0.3048)
			(end 0.120396 0.2794)
			(stroke
				(width 0.1)
				(type default)
			)
			(layer "F.Fab")
		)
		(fp_line
			(start 0.12065 -0.3048)
			(end 0.67945 -0.3048)
			(stroke
				(width 0.1)
				(type default)
			)
			(layer "F.Fab")
		)
		(fp_line
			(start 0.12065 -0.2794)
			(end 0.12065 -0.3048)
			(stroke
				(width 0.1)
				(type default)
			)
			(layer "F.Fab")
		)
		(fp_line
			(start 0.67945 -0.3048)
			(end 0.67945 0.3048)
			(stroke
				(width 0.1)
				(type default)
			)
			(layer "F.Fab")
		)
		(fp_line
			(start 0.67945 0.3048)
			(end 0.120396 0.3048)
			(stroke
				(width 0.1)
				(type default)
			)
			(layer "F.Fab")
		)
		(pad "1" smd circle
			(at -0.40005 0)
			(size 0 0)
			(layers "F.Cu" "F.Mask" "F.Paste")
			(net "SMB_VR_3V3AUX_SCL_R1")
		)
		(pad "2" smd circle
			(at 0.40005 0)
			(size 0 0)
			(layers "F.Cu" "F.Mask" "F.Paste")
			(net "SMB_SEN_TIC_3V3AUX_SCL")
		)
	)
)
